# TIMECARD (Time Appliance Project (Time Card)) — schematic netlist excerpt (pin names and nets, part order shuffled) for the footprints in the layout excerpt that follows; sources: Cadence DE-HDL packaged netlist, KiCad conversion of R4006-B0001-02_R01.brd

C259  CAPACITOR  0.022UF 25V 10%  pkg SMC_0402R_H022  page 29 : \1\ = XP1R0V_SS ; \2\ = XP1R0V_AGND
R97  RESISTOR  0OHM -  pkg SMC_0402R_H016  page 21 : \1\ = R_MAC_USB_DP ; \2\ = MUX_USB_DP

(kicad_pcb
	(version 20260206)
	(generator "pcbnew")
	(generator_version "10.0")
	(general
		(thickness 1.6)
		(legacy_teardrops no)
	)
	(paper "A4")
	(title_block
		(title "timecard-production-celestica-r4006 — R4006-B0001-02_R01.brd")
		(comment 1 "Time Appliance Project (Time Card) / footprints 166-167 of 1113")
	)
	(layers
		(0 "F.Cu" signal "TOP")
		(4 "In1.Cu" signal "L02_GND1")
		(6 "In2.Cu" signal "L03_SIG1")
		(8 "In3.Cu" signal "L04_GND2")
		(10 "In4.Cu" signal "L05_VCC1")
		(12 "In5.Cu" signal "L06_VCC2")
		(14 "In6.Cu" signal "L07_GND3")
		(16 "In7.Cu" signal "L08_SIG2")
		(18 "In8.Cu" signal "L09_GND4")
		(2 "B.Cu" signal "BOTTOM")
		(9 "F.Adhes" user "F.Adhesive")
		(11 "B.Adhes" user "B.Adhesive")
		(13 "F.Paste" user "Package Geometry/Pastemask Top")
		(15 "B.Paste" user "Package Geometry/Pastemask Bottom")
		(5 "F.SilkS" user "Ref Des/Silkscreen Top")
		(7 "B.SilkS" user "Ref Des/Silkscreen Bottom")
		(1 "F.Mask" user "Board Geometry/Soldermask Top")
		(3 "B.Mask" user "Board Geometry/Soldermask Bottom")
		(17 "Dwgs.User" user "User.Drawings")
		(19 "Cmts.User" user "User.Comments")
		(21 "Eco1.User" user "User.Eco1")
		(23 "Eco2.User" user "User.Eco2")
		(25 "Edge.Cuts" user "Board Geometry/Outline")
		(27 "Margin" user)
		(31 "F.CrtYd" user "Package Geometry/Place Bound Top")
		(29 "B.CrtYd" user "Package Geometry/Place Bound Bottom")
		(35 "F.Fab" user "Ref Des/Assembly Top")
		(33 "B.Fab" user "Ref Des/Assembly Bottom")
	)
	(footprint ""
		(layer "F.Cu")
		(at 142.24 -59.563 90)
		(property "Reference" "C259"
			(at 3.048 -1.86563 90)
			(unlocked yes)
			(layer "F.SilkS")
			(effects
				(font
					(size 0.7874 0.5842)
					(thickness 0.1524)
				)
			)
		)
		(property "Value" "VAL*"
			(at 0.0762 2.067306 90)
			(unlocked yes)
			(layer "F.Fab")
			(hide yes)
			(effects
				(font
					(size 0.7874 0.5842)
					(thickness 0.1524)
				)
			)
		)
		(property "Device Type" "CAPACITOR-G105-0B223-EK,0.022UA"
			(at 0.0508 1.127506 90)
			(unlocked yes)
			(layer "F.Fab")
			(hide yes)
			(effects
				(font
					(size 0.7874 0.5842)
					(thickness 0.1524)
				)
			)
		)
		(property "User Part Number" "PARTNUM*"
			(at 0.1016 4.023106 90)
			(unlocked yes)
			(layer "Cmts.User")
			(hide yes)
			(effects
				(font
					(size 0.7874 0.5842)
					(thickness 0.1524)
				)
			)
		)
		(property "Tolerance" "TOL*"
			(at 0.0762 3.032506 90)
			(unlocked yes)
			(layer "Cmts.User")
			(hide yes)
			(effects
				(font
					(size 0.7874 0.5842)
					(thickness 0.1524)
				)
			)
		)
		(duplicate_pad_numbers_are_jumpers no)
		(fp_line
			(start 1.143 -0.5588)
			(end -1.143 -0.5588)
			(stroke
				(width 0.1)
				(type default)
			)
			(layer "F.SilkS")
		)
		(fp_line
			(start -1.143 -0.5588)
			(end -1.143 0.5588)
			(stroke
				(width 0.1)
				(type default)
			)
			(layer "F.SilkS")
		)
		(fp_line
			(start 1.143 0.5588)
			(end 1.143 -0.5588)
			(stroke
				(width 0.1)
				(type default)
			)
			(layer "F.SilkS")
		)
		(fp_line
			(start -1.143 0.5588)
			(end 1.143 0.5588)
			(stroke
				(width 0.1)
				(type default)
			)
			(layer "F.SilkS")
		)
		(fp_rect
			(start -1.143 -0.5588)
			(end 1.143 0.5588)
			(stroke
				(width 0)
				(type default)
			)
			(fill no)
			(layer "F.CrtYd")
		)
		(fp_line
			(start 0.508 -0.3048)
			(end -0.508 -0.3048)
			(stroke
				(width 0.1)
				(type default)
			)
			(layer "F.Fab")
		)
		(fp_line
			(start -0.508 -0.3048)
			(end -0.508 0.3048)
			(stroke
				(width 0.1)
				(type default)
			)
			(layer "F.Fab")
		)
		(fp_line
			(start 0.508 0.3048)
			(end 0.508 -0.3048)
			(stroke
				(width 0.1)
				(type default)
			)
			(layer "F.Fab")
		)
		(fp_line
			(start -0.508 0.3048)
			(end 0.508 0.3048)
			(stroke
				(width 0.1)
				(type default)
			)
			(layer "F.Fab")
		)
		(pad "1" smd rect
			(at -0.5334 0 90)
			(size 0.7112 0.6096)
			(layers "F.Cu" "F.Mask" "F.Paste")
			(net "XP1R0V_SS")
		)
		(pad "2" smd rect
			(at 0.5334 0 90)
			(size 0.7112 0.6096)
			(layers "F.Cu" "F.Mask" "F.Paste")
			(net "XP1R0V_AGND")
		)
		(zone
			(layer "F.Cu")
			(hatch none 0.5)
			(connect_pads
				(clearance 0)
			)
			(min_thickness 0.25)
			(keepout
				(tracks allowed)
				(vias not_allowed)
				(pads allowed)
				(copperpour not_allowed)
				(footprints allowed)
			)
			(placement
				(enabled no)
				(sheetname "")
			)
			(fill
				(thermal_gap 0.5)
				(thermal_bridge_width 0.5)
				(island_removal_mode 0)
			)
			(polygon
				(pts
					(xy 141.9352 -59.4868) (xy 142.5448 -59.4868) (xy 142.5448 -59.6392) (xy 141.9352 -59.6392)
				)
			)
		)
	)
	(footprint ""
		(layer "F.Cu")
		(at 79.756 -48.133)
		(property "Reference" "R97"
			(at 0.127 14.26337 0)
			(unlocked yes)
			(layer "F.SilkS")
			(effects
				(font
					(size 0.7874 0.5842)
					(thickness 0.1524)
				)
			)
		)
		(property "Value" "VAL*"
			(at 0.02032 2.13233 0)
			(unlocked yes)
			(layer "F.Fab")
			(hide yes)
			(effects
				(font
					(size 0.7874 0.5842)
					(thickness 0.1524)
				)
			)
		)
		(property "Device Type" "RESISTOR-G155-100R0-J0,0OHM,-"
			(at 0.008382 1.210564 0)
			(unlocked yes)
			(layer "F.Fab")
			(hide yes)
			(effects
				(font
					(size 0.7874 0.5842)
					(thickness 0.1524)
				)
			)
		)
		(property "User Part Number" "PARTNUM*"
			(at 0.02032 4.024884 0)
			(unlocked yes)
			(layer "Cmts.User")
			(hide yes)
			(effects
				(font
					(size 0.7874 0.5842)
					(thickness 0.1524)
				)
			)
		)
		(property "Tolerance" "TOL*"
			(at 0.044704 3.05435 0)
			(unlocked yes)
			(layer "Cmts.User")
			(hide yes)
			(effects
				(font
					(size 0.7874 0.5842)
					(thickness 0.1524)
				)
			)
		)
		(duplicate_pad_numbers_are_jumpers no)
		(fp_line
			(start -1.143 -0.5588)
			(end -1.143 0.5588)
			(stroke
				(width 0.1)
				(type default)
			)
			(layer "F.SilkS")
		)
		(fp_line
			(start -1.143 0.5588)
			(end 1.143 0.5588)
			(stroke
				(width 0.1)
				(type default)
			)
			(layer "F.SilkS")
		)
		(fp_line
			(start 1.143 -0.5588)
			(end -1.143 -0.5588)
			(stroke
				(width 0.1)
				(type default)
			)
			(layer "F.SilkS")
		)
		(fp_line
			(start 1.143 0.5588)
			(end 1.143 -0.5588)
			(stroke
				(width 0.1)
				(type default)
			)
			(layer "F.SilkS")
		)
		(fp_rect
			(start -1.143 0.5588)
			(end 1.143 -0.5588)
			(stroke
				(width 0)
				(type default)
			)
			(fill no)
			(layer "F.CrtYd")
		)
		(fp_line
			(start -0.508 -0.3048)
			(end -0.508 0.3048)
			(stroke
				(width 0.1)
				(type default)
			)
			(layer "F.Fab")
		)
		(fp_line
			(start -0.508 0.3048)
			(end 0.508 0.3048)
			(stroke
				(width 0.1)
				(type default)
			)
			(layer "F.Fab")
		)
		(fp_line
			(start 0.508 -0.3048)
			(end -0.508 -0.3048)
			(stroke
				(width 0.1)
				(type default)
			)
			(layer "F.Fab")
		)
		(fp_line
			(start 0.508 0.3048)
			(end 0.508 -0.3048)
			(stroke
				(width 0.1)
				(type default)
			)
			(layer "F.Fab")
		)
		(pad "1" smd rect
			(at -0.5334 0)
			(size 0.7112 0.6096)
			(layers "F.Cu" "F.Mask" "F.Paste")
			(net "R_MAC_USB_DP")
		)
		(pad "2" smd rect
			(at 0.5334 0)
			(size 0.7112 0.6096)
			(layers "F.Cu" "F.Mask" "F.Paste")
			(net "MUX_USB_DP")
		)
		(zone
			(layer "F.Cu")
			(hatch none 0.5)
			(connect_pads
				(clearance 0)
			)
			(min_thickness 0.25)
			(keepout
				(tracks allowed)
				(vias not_allowed)
				(pads allowed)
				(copperpour not_allowed)
				(footprints allowed)
			)
			(placement
				(enabled no)
				(sheetname "")
			)
			(fill
				(thermal_gap 0.5)
				(thermal_bridge_width 0.5)
				(island_removal_mode 0)
			)
			(polygon
				(pts
					(xy 79.6798 -47.8282) (xy 79.8322 -47.8282) (xy 79.8322 -48.4378) (xy 79.6798 -48.4378)
				)
			)
		)
	)
)
